(kicad_pcb
	(version 20260206)
	(generator "pcbnew")
	(generator_version "10.0")
	(general
		(thickness 1.6)
		(legacy_teardrops no)
	)
	(paper "A4")
	(title_block
		(title "04192023_DAF0TMB3IC0_F0TG_MB_C_brd_V02_OCP.brd")
		(comment 1 "Grand Teton / footprints 3531-3536 of 8354")
	)
	(layers
		(0 "F.Cu" signal "TOP")
		(4 "In1.Cu" signal "GND")
		(6 "In2.Cu" signal "IN1")
		(8 "In3.Cu" signal "GND1")
		(10 "In4.Cu" signal "IN2")
		(12 "In5.Cu" signal "GND2")
		(14 "In6.Cu" signal "IN3")
		(16 "In7.Cu" signal "GND3")
		(18 "In8.Cu" signal "VCC")
		(20 "In9.Cu" signal "VCC1")
		(22 "In10.Cu" signal "GND4")
		(24 "In11.Cu" signal "IN4")
		(26 "In12.Cu" signal "GND5")
		(28 "In13.Cu" signal "IN5")
		(30 "In14.Cu" signal "GND6")
		(32 "In15.Cu" signal "IN6")
		(34 "In16.Cu" signal "GND7")
		(2 "B.Cu" signal "BOTTOM")
		(9 "F.Adhes" user "F.Adhesive")
		(11 "B.Adhes" user "B.Adhesive")
		(13 "F.Paste" user "Package Geometry/Pastemask Top")
		(15 "B.Paste" user "Package Geometry/Pastemask Bottom")
		(5 "F.SilkS" user "Ref Des/Silkscreen Top")
		(7 "B.SilkS" user "Ref Des/Silkscreen Bottom")
		(1 "F.Mask" user "Board Geometry/Soldermask Top")
		(3 "B.Mask" user "Board Geometry/Soldermask Bottom")
		(17 "Dwgs.User" user "User.Drawings")
		(19 "Cmts.User" user "User.Comments")
		(21 "Eco1.User" user "User.Eco1")
		(23 "Eco2.User" user "User.Eco2")
		(25 "Edge.Cuts" user "Board Geometry/Outline")
		(27 "Margin" user)
		(31 "F.CrtYd" user "Package Geometry/Place Bound Top")
		(29 "B.CrtYd" user "Package Geometry/Place Bound Bottom")
		(35 "F.Fab" user "Ref Des/Assembly Top")
		(33 "B.Fab" user "Ref Des/Assembly Bottom")
	)
	(footprint ""
		(layer "F.Cu")
		(at 367.504726 -27.904694 -90)
		(property "Reference" "C363"
			(at 0 0 270)
			(layer "F.SilkS")
			(hide yes)
			(effects
				(font
					(size 1.27 1.27)
				)
			)
		)
		(property "Value" ""
			(at 0 0 270)
			(layer "F.Fab")
			(effects
				(font
					(size 1.27 1.27)
				)
			)
		)
		(duplicate_pad_numbers_are_jumpers no)
		(fp_line
			(start -0.7874 0.4064)
			(end -0.7874 -0.4064)
			(stroke
				(width 0.1524)
				(type default)
			)
			(layer "F.SilkS")
		)
		(fp_line
			(start 0.7874 0.4064)
			(end -0.7874 0.4064)
			(stroke
				(width 0.1524)
				(type default)
			)
			(layer "F.SilkS")
		)
		(fp_line
			(start -0.7874 -0.4064)
			(end 0.7874 -0.4064)
			(stroke
				(width 0.1524)
				(type default)
			)
			(layer "F.SilkS")
		)
		(fp_line
			(start 0.7874 -0.4064)
			(end 0.7874 0.4064)
			(stroke
				(width 0.1524)
				(type default)
			)
			(layer "F.SilkS")
		)
		(fp_line
			(start -0.67945 0.3048)
			(end -0.67945 -0.305054)
			(stroke
				(width 0.1)
				(type default)
			)
			(layer "F.Fab")
		)
		(fp_line
			(start -0.12065 0.3048)
			(end -0.67945 0.3048)
			(stroke
				(width 0.1)
				(type default)
			)
			(layer "F.Fab")
		)
		(fp_line
			(start 0.120396 0.3048)
			(end 0.120396 0.2794)
			(stroke
				(width 0.1)
				(type default)
			)
			(layer "F.Fab")
		)
		(fp_line
			(start 0.67945 0.3048)
			(end 0.120396 0.3048)
			(stroke
				(width 0.1)
				(type default)
			)
			(layer "F.Fab")
		)
		(fp_line
			(start -0.12065 0.2794)
			(end -0.12065 0.3048)
			(stroke
				(width 0.1)
				(type default)
			)
			(layer "F.Fab")
		)
		(fp_line
			(start 0.120396 0.2794)
			(end -0.12065 0.2794)
			(stroke
				(width 0.1)
				(type default)
			)
			(layer "F.Fab")
		)
		(fp_line
			(start -0.12065 -0.2794)
			(end 0.12065 -0.2794)
			(stroke
				(width 0.1)
				(type default)
			)
			(layer "F.Fab")
		)
		(fp_line
			(start 0.12065 -0.2794)
			(end 0.12065 -0.3048)
			(stroke
				(width 0.1)
				(type default)
			)
			(layer "F.Fab")
		)
		(fp_line
			(start 0.12065 -0.3048)
			(end 0.67945 -0.3048)
			(stroke
				(width 0.1)
				(type default)
			)
			(layer "F.Fab")
		)
		(fp_line
			(start 0.67945 -0.3048)
			(end 0.67945 0.3048)
			(stroke
				(width 0.1)
				(type default)
			)
			(layer "F.Fab")
		)
		(fp_line
			(start -0.67945 -0.305054)
			(end -0.12065 -0.305054)
			(stroke
				(width 0.1)
				(type default)
			)
			(layer "F.Fab")
		)
		(fp_line
			(start -0.12065 -0.305054)
			(end -0.12065 -0.2794)
			(stroke
				(width 0.1)
				(type default)
			)
			(layer "F.Fab")
		)
		(pad "1" smd circle
			(at -0.40005 0 270)
			(size 0 0)
			(layers "F.Cu" "F.Mask" "F.Paste")
			(net "UART_CPU0_LVC3_UART0_TX")
		)
		(pad "2" smd circle
			(at 0.40005 0 270)
			(size 0 0)
			(layers "F.Cu" "F.Mask" "F.Paste")
			(net "GND")
		)
	)
	(footprint ""
		(layer "F.Cu")
		(at 425.121324 -396.748 90)
		(property "Reference" "C668"
			(at 0 0 90)
			(layer "F.SilkS")
			(hide yes)
			(effects
				(font
					(size 1.27 1.27)
				)
			)
		)
		(property "Value" ""
			(at 0 0 90)
			(layer "F.Fab")
			(effects
				(font
					(size 1.27 1.27)
				)
			)
		)
		(duplicate_pad_numbers_are_jumpers no)
		(fp_line
			(start 0.7874 -0.4064)
			(end 0.7874 0.4064)
			(stroke
				(width 0.1524)
				(type default)
			)
			(layer "F.SilkS")
		)
		(fp_line
			(start -0.7874 -0.4064)
			(end 0.7874 -0.4064)
			(stroke
				(width 0.1524)
				(type default)
			)
			(layer "F.SilkS")
		)
		(fp_line
			(start 0.7874 0.4064)
			(end -0.7874 0.4064)
			(stroke
				(width 0.1524)
				(type default)
			)
			(layer "F.SilkS")
		)
		(fp_line
			(start -0.7874 0.4064)
			(end -0.7874 -0.4064)
			(stroke
				(width 0.1524)
				(type default)
			)
			(layer "F.SilkS")
		)
		(fp_line
			(start -0.12065 -0.305054)
			(end -0.12065 -0.2794)
			(stroke
				(width 0.1)
				(type default)
			)
			(layer "F.Fab")
		)
		(fp_line
			(start -0.67945 -0.305054)
			(end -0.12065 -0.305054)
			(stroke
				(width 0.1)
				(type default)
			)
			(layer "F.Fab")
		)
		(fp_line
			(start 0.67945 -0.3048)
			(end 0.67945 0.3048)
			(stroke
				(width 0.1)
				(type default)
			)
			(layer "F.Fab")
		)
		(fp_line
			(start 0.12065 -0.3048)
			(end 0.67945 -0.3048)
			(stroke
				(width 0.1)
				(type default)
			)
			(layer "F.Fab")
		)
		(fp_line
			(start 0.12065 -0.2794)
			(end 0.12065 -0.3048)
			(stroke
				(width 0.1)
				(type default)
			)
			(layer "F.Fab")
		)
		(fp_line
			(start -0.12065 -0.2794)
			(end 0.12065 -0.2794)
			(stroke
				(width 0.1)
				(type default)
			)
			(layer "F.Fab")
		)
		(fp_line
			(start 0.120396 0.2794)
			(end -0.12065 0.2794)
			(stroke
				(width 0.1)
				(type default)
			)
			(layer "F.Fab")
		)
		(fp_line
			(start -0.12065 0.2794)
			(end -0.12065 0.3048)
			(stroke
				(width 0.1)
				(type default)
			)
			(layer "F.Fab")
		)
		(fp_line
			(start 0.67945 0.3048)
			(end 0.120396 0.3048)
			(stroke
				(width 0.1)
				(type default)
			)
			(layer "F.Fab")
		)
		(fp_line
			(start 0.120396 0.3048)
			(end 0.120396 0.2794)
			(stroke
				(width 0.1)
				(type default)
			)
			(layer "F.Fab")
		)
		(fp_line
			(start -0.12065 0.3048)
			(end -0.67945 0.3048)
			(stroke
				(width 0.1)
				(type default)
			)
			(layer "F.Fab")
		)
		(fp_line
			(start -0.67945 0.3048)
			(end -0.67945 -0.305054)
			(stroke
				(width 0.1)
				(type default)
			)
			(layer "F.Fab")
		)
		(pad "1" smd circle
			(at -0.40005 0 90)
			(size 0 0)
			(layers "F.Cu" "F.Mask" "F.Paste")
			(net "P1V8_CPU0_RT2_1A")
		)
		(pad "2" smd circle
			(at 0.40005 0 90)
			(size 0 0)
			(layers "F.Cu" "F.Mask" "F.Paste")
			(net "GND")
		)
	)
	(footprint ""
		(layer "F.Cu")
		(at 162.052 -107.696 90)
		(property "Reference" "C9005"
			(at 0 0 90)
			(layer "F.SilkS")
			(hide yes)
			(effects
				(font
					(size 1.27 1.27)
				)
			)
		)
		(property "Value" ""
			(at 0 0 90)
			(layer "F.Fab")
			(effects
				(font
					(size 1.27 1.27)
				)
			)
		)
		(duplicate_pad_numbers_are_jumpers no)
		(fp_line
			(start 0.7874 -0.4064)
			(end 0.7874 0.4064)
			(stroke
				(width 0.1524)
				(type default)
			)
			(layer "F.SilkS")
		)
		(fp_line
			(start -0.7874 -0.4064)
			(end 0.7874 -0.4064)
			(stroke
				(width 0.1524)
				(type default)
			)
			(layer "F.SilkS")
		)
		(fp_line
			(start 0.7874 0.4064)
			(end -0.7874 0.4064)
			(stroke
				(width 0.1524)
				(type default)
			)
			(layer "F.SilkS")
		)
		(fp_line
			(start -0.7874 0.4064)
			(end -0.7874 -0.4064)
			(stroke
				(width 0.1524)
				(type default)
			)
			(layer "F.SilkS")
		)
		(fp_line
			(start -0.12065 -0.305054)
			(end -0.12065 -0.2794)
			(stroke
				(width 0.1)
				(type default)
			)
			(layer "F.Fab")
		)
		(fp_line
			(start -0.67945 -0.305054)
			(end -0.12065 -0.305054)
			(stroke
				(width 0.1)
				(type default)
			)
			(layer "F.Fab")
		)
		(fp_line
			(start 0.67945 -0.3048)
			(end 0.67945 0.3048)
			(stroke
				(width 0.1)
				(type default)
			)
			(layer "F.Fab")
		)
		(fp_line
			(start 0.12065 -0.3048)
			(end 0.67945 -0.3048)
			(stroke
				(width 0.1)
				(type default)
			)
			(layer "F.Fab")
		)
		(fp_line
			(start 0.12065 -0.2794)
			(end 0.12065 -0.3048)
			(stroke
				(width 0.1)
				(type default)
			)
			(layer "F.Fab")
		)
		(fp_line
			(start -0.12065 -0.2794)
			(end 0.12065 -0.2794)
			(stroke
				(width 0.1)
				(type default)
			)
			(layer "F.Fab")
		)
		(fp_line
			(start 0.120396 0.2794)
			(end -0.12065 0.2794)
			(stroke
				(width 0.1)
				(type default)
			)
			(layer "F.Fab")
		)
		(fp_line
			(start -0.12065 0.2794)
			(end -0.12065 0.3048)
			(stroke
				(width 0.1)
				(type default)
			)
			(layer "F.Fab")
		)
		(fp_line
			(start 0.67945 0.3048)
			(end 0.120396 0.3048)
			(stroke
				(width 0.1)
				(type default)
			)
			(layer "F.Fab")
		)
		(fp_line
			(start 0.120396 0.3048)
			(end 0.120396 0.2794)
			(stroke
				(width 0.1)
				(type default)
			)
			(layer "F.Fab")
		)
		(fp_line
			(start -0.12065 0.3048)
			(end -0.67945 0.3048)
			(stroke
				(width 0.1)
				(type default)
			)
			(layer "F.Fab")
		)
		(fp_line
			(start -0.67945 0.3048)
			(end -0.67945 -0.305054)
			(stroke
				(width 0.1)
				(type default)
			)
			(layer "F.Fab")
		)
		(pad "1" smd circle
			(at -0.40005 0 90)
			(size 0 0)
			(layers "F.Cu" "F.Mask" "F.Paste")
			(net "IRQ_HSC_FAULT_BUF_N")
		)
		(pad "2" smd circle
			(at 0.40005 0 90)
			(size 0 0)
			(layers "F.Cu" "F.Mask" "F.Paste")
			(net "GND")
		)
	)
	(footprint ""
		(layer "F.Cu")
		(at 329.838558 -38.409118)
		(property "Reference" "C1768"
			(at 0 0 0)
			(layer "F.SilkS")
			(hide yes)
			(effects
				(font
					(size 1.27 1.27)
				)
			)
		)
		(property "Value" ""
			(at 0 0 0)
			(layer "F.Fab")
			(effects
				(font
					(size 1.27 1.27)
				)
			)
		)
		(duplicate_pad_numbers_are_jumpers no)
		(fp_line
			(start -1.524 -0.762)
			(end 1.524 -0.762)
			(stroke
				(width 0.1524)
				(type default)
			)
			(layer "F.SilkS")
		)
		(fp_line
			(start -1.524 0.762)
			(end -1.524 -0.762)
			(stroke
				(width 0.1524)
				(type default)
			)
			(layer "F.SilkS")
		)
		(fp_line
			(start 1.524 -0.762)
			(end 1.524 0.762)
			(stroke
				(width 0.1524)
				(type default)
			)
			(layer "F.SilkS")
		)
		(fp_line
			(start 1.524 0.762)
			(end -1.524 0.762)
			(stroke
				(width 0.1524)
				(type default)
			)
			(layer "F.SilkS")
		)
		(fp_line
			(start -1.1049 -0.724916)
			(end -1.1049 0.724916)
			(stroke
				(width 0.1)
				(type default)
			)
			(layer "F.Fab")
		)
		(fp_line
			(start -1.1049 0.724916)
			(end 1.1049 0.724916)
			(stroke
				(width 0.1)
				(type default)
			)
			(layer "F.Fab")
		)
		(fp_line
			(start 1.1049 -0.724916)
			(end -1.1049 -0.724916)
			(stroke
				(width 0.1)
				(type default)
			)
			(layer "F.Fab")
		)
		(fp_line
			(start 1.1049 0.724916)
			(end 1.1049 -0.724916)
			(stroke
				(width 0.1)
				(type default)
			)
			(layer "F.Fab")
		)
		(pad "1" smd rect
			(at -0.889 0 180)
			(size 1.016 1.27)
			(layers "F.Cu" "F.Mask" "F.Paste")
			(net "P3V3_MAX11617_VDD")
		)
		(pad "2" smd rect
			(at 0.889 0 180)
			(size 1.016 1.27)
			(layers "F.Cu" "F.Mask" "F.Paste")
			(net "GND")
		)
	)
	(footprint ""
		(layer "F.Cu")
		(at 393.353798 -320.627756 180)
		(property "Reference" "C5023"
			(at 0 0 180)
			(layer "F.SilkS")
			(hide yes)
			(effects
				(font
					(size 1.27 1.27)
				)
			)
		)
		(property "Value" ""
			(at 0 0 180)
			(layer "F.Fab")
			(effects
				(font
					(size 1.27 1.27)
				)
			)
		)
		(duplicate_pad_numbers_are_jumpers no)
		(fp_line
			(start 0.7874 0.4064)
			(end -0.7874 0.4064)
			(stroke
				(width 0.1524)
				(type default)
			)
			(layer "F.SilkS")
		)
		(fp_line
			(start 0.7874 -0.4064)
			(end 0.7874 0.4064)
			(stroke
				(width 0.1524)
				(type default)
			)
			(layer "F.SilkS")
		)
		(fp_line
			(start -0.7874 0.4064)
			(end -0.7874 -0.4064)
			(stroke
				(width 0.1524)
				(type default)
			)
			(layer "F.SilkS")
		)
		(fp_line
			(start -0.7874 -0.4064)
			(end 0.7874 -0.4064)
			(stroke
				(width 0.1524)
				(type default)
			)
			(layer "F.SilkS")
		)
		(fp_line
			(start 0.67945 0.3048)
			(end 0.120396 0.3048)
			(stroke
				(width 0.1)
				(type default)
			)
			(layer "F.Fab")
		)
		(fp_line
			(start 0.67945 -0.3048)
			(end 0.67945 0.3048)
			(stroke
				(width 0.1)
				(type default)
			)
			(layer "F.Fab")
		)
		(fp_line
			(start 0.12065 -0.2794)
			(end 0.12065 -0.3048)
			(stroke
				(width 0.1)
				(type default)
			)
			(layer "F.Fab")
		)
		(fp_line
			(start 0.12065 -0.3048)
			(end 0.67945 -0.3048)
			(stroke
				(width 0.1)
				(type default)
			)
			(layer "F.Fab")
		)
		(fp_line
			(start 0.120396 0.3048)
			(end 0.120396 0.2794)
			(stroke
				(width 0.1)
				(type default)
			)
			(layer "F.Fab")
		)
		(fp_line
			(start 0.120396 0.2794)
			(end -0.12065 0.2794)
			(stroke
				(width 0.1)
				(type default)
			)
			(layer "F.Fab")
		)
		(fp_line
			(start -0.12065 0.3048)
			(end -0.67945 0.3048)
			(stroke
				(width 0.1)
				(type default)
			)
			(layer "F.Fab")
		)
		(fp_line
			(start -0.12065 0.2794)
			(end -0.12065 0.3048)
			(stroke
				(width 0.1)
				(type default)
			)
			(layer "F.Fab")
		)
		(fp_line
			(start -0.12065 -0.2794)
			(end 0.12065 -0.2794)
			(stroke
				(width 0.1)
				(type default)
			)
			(layer "F.Fab")
		)
		(fp_line
			(start -0.12065 -0.305054)
			(end -0.12065 -0.2794)
			(stroke
				(width 0.1)
				(type default)
			)
			(layer "F.Fab")
		)
		(fp_line
			(start -0.67945 0.3048)
			(end -0.67945 -0.305054)
			(stroke
				(width 0.1)
				(type default)
			)
			(layer "F.Fab")
		)
		(fp_line
			(start -0.67945 -0.305054)
			(end -0.12065 -0.305054)
			(stroke
				(width 0.1)
				(type default)
			)
			(layer "F.Fab")
		)
		(pad "1" smd circle
			(at -0.40005 0 180)
			(size 0 0)
			(layers "F.Cu" "F.Mask" "F.Paste")
			(net "RST_CPU0_RSMRST_N")
		)
		(pad "2" smd circle
			(at 0.40005 0 180)
			(size 0 0)
			(layers "F.Cu" "F.Mask" "F.Paste")
			(net "GND")
		)
	)
	(footprint ""
		(layer "F.Cu")
		(at 51.435 -435.61)
		(property "Reference" "U252"
			(at -1.821434 -3.3528 0)
			(unlocked yes)
			(layer "F.SilkS")
			(effects
				(font
					(size 0.7874 0.5842)
					(thickness 0.1524)
				)
				(justify left)
			)
		)
		(property "Value" ""
			(at 0 0 0)
			(layer "F.Fab")
			(effects
				(font
					(size 1.27 1.27)
				)
			)
		)
		(duplicate_pad_numbers_are_jumpers no)
		(fp_line
			(start -1.3462 -1.100074)
			(end -0.670052 -1.100074)
			(stroke
				(width 0.1524)
				(type default)
			)
			(layer "F.SilkS")
		)
		(fp_line
			(start -1.3462 1.100074)
			(end -1.3462 -1.100074)
			(stroke
				(width 0.1524)
				(type default)
			)
			(layer "F.SilkS")
		)
		(fp_line
			(start -0.670052 -1.100074)
			(end 0 -0.381)
			(stroke
				(width 0.1524)
				(type default)
			)
			(layer "F.SilkS")
		)
		(fp_line
			(start 0 -0.381)
			(end 0.670052 -1.100074)
			(stroke
				(width 0.1524)
				(type default)
			)
			(layer "F.SilkS")
		)
		(fp_line
			(start 0.670052 -1.100074)
			(end 1.3462 -1.100074)
			(stroke
				(width 0.1524)
				(type default)
			)
			(layer "F.SilkS")
		)
		(fp_line
			(start 1.3462 -1.100074)
			(end 1.3462 1.100074)
			(stroke
				(width 0.1524)
				(type default)
			)
			(layer "F.SilkS")
		)
		(fp_line
			(start 1.3462 1.100074)
			(end -1.3462 1.100074)
			(stroke
				(width 0.1524)
				(type default)
			)
			(layer "F.SilkS")
		)
		(fp_poly
			(pts
				(xy -2.953512 -1.926844) (xy -2.52095 -2.554224) (xy -2.109978 -1.807972)
			)
			(stroke
				(width 0)
				(type default)
			)
			(fill yes)
			(layer "F.SilkS")
		)
		(fp_line
			(start -1.100074 -0.8001)
			(end -0.670052 -0.8001)
			(stroke
				(width 0.1)
				(type default)
			)
			(layer "F.Fab")
		)
		(fp_line
			(start -1.100074 0.8001)
			(end -1.100074 -0.8001)
			(stroke
				(width 0.1)
				(type default)
			)
			(layer "F.Fab")
		)
		(fp_line
			(start -0.670052 -1.100074)
			(end 0.670052 -1.100074)
			(stroke
				(width 0.1)
				(type default)
			)
			(layer "F.Fab")
		)
		(fp_line
			(start -0.670052 -0.8001)
			(end -0.670052 -1.100074)
			(stroke
				(width 0.1)
				(type default)
			)
			(layer "F.Fab")
		)
		(fp_line
			(start -0.670052 0.8001)
			(end -1.100074 0.8001)
			(stroke
				(width 0.1)
				(type default)
			)
			(layer "F.Fab")
		)
		(fp_line
			(start -0.670052 0.8001)
			(end -0.670052 -0.8001)
			(stroke
				(width 0.1)
				(type default)
			)
			(layer "F.Fab")
		)
		(fp_line
			(start -0.670052 1.100074)
			(end -0.670052 0.8001)
			(stroke
				(width 0.1)
				(type default)
			)
			(layer "F.Fab")
		)
		(fp_line
			(start 0.670052 -1.100074)
			(end 0.670052 -0.8001)
			(stroke
				(width 0.1)
				(type default)
			)
			(layer "F.Fab")
		)
		(fp_line
			(start 0.670052 -0.8001)
			(end 0.670052 0.8001)
			(stroke
				(width 0.1)
				(type default)
			)
			(layer "F.Fab")
		)
		(fp_line
			(start 0.670052 -0.8001)
			(end 1.100074 -0.8001)
			(stroke
				(width 0.1)
				(type default)
			)
			(layer "F.Fab")
		)
		(fp_line
			(start 0.670052 0.8001)
			(end 0.670052 1.100074)
			(stroke
				(width 0.1)
				(type default)
			)
			(layer "F.Fab")
		)
		(fp_line
			(start 0.670052 1.100074)
			(end -0.670052 1.100074)
			(stroke
				(width 0.1)
				(type default)
			)
			(layer "F.Fab")
		)
		(fp_line
			(start 1.100074 -0.8001)
			(end 1.100074 0.8001)
			(stroke
				(width 0.1)
				(type default)
			)
			(layer "F.Fab")
		)
		(fp_line
			(start 1.100074 0.8001)
			(end 0.670052 0.8001)
			(stroke
				(width 0.1)
				(type default)
			)
			(layer "F.Fab")
		)
		(fp_poly
			(pts
				(xy -1.524 -0.649986) (xy -2.286 -1.030986) (xy -2.286 -0.268986)
			)
			(stroke
				(width 0)
				(type default)
			)
			(fill yes)
			(layer "F.Fab")
		)
		(pad "1" smd rect
			(at -0.94996 -0.649986 270)
			(size 0.4064 0.508)
			(layers "F.Cu" "F.Mask" "F.Paste")
			(net "RST_PERST_CPU1_SWB_R_N")
		)
		(pad "2" smd rect
			(at -0.94996 0 270)
			(size 0.4064 0.508)
			(layers "F.Cu" "F.Mask" "F.Paste")
			(net "GND")
		)
		(pad "3" smd rect
			(at -0.94996 0.649986 270)
			(size 0.4064 0.508)
			(layers "F.Cu" "F.Mask" "F.Paste")
			(net "RST_PERST_CPU1_SWB_1_R_N")
		)
		(pad "4" smd rect
			(at 0.94996 0.649986 270)
			(size 0.4064 0.508)
			(layers "F.Cu" "F.Mask" "F.Paste")
			(net "RST_PERST_2_SWB_BUF_R_N")
		)
		(pad "5" smd rect
			(at 0.94996 0 270)
			(size 0.4064 0.508)
			(layers "F.Cu" "F.Mask" "F.Paste")
			(net "P3V3_AUX")
		)
		(pad "6" smd rect
			(at 0.94996 -0.649986 270)
			(size 0.4064 0.508)
			(layers "F.Cu" "F.Mask" "F.Paste")
			(net "RST_PERST_0_SWB_BUF_R_N")
		)
	)
)
